# T6G (Grand Teton) — schematic netlist excerpt (pin names and nets, part order shuffled) for the footprints in the layout excerpt that follows; sources: Cadence DE-HDL packaged netlist, KiCad conversion of 04192023_DAF0TMB3IC0_F0TG_MB_C_brd_V02_OCP.brd

R234  Q_RES  0 5% CHIP  pkg 0402LF  page 82 : A = CPU1_XTRIG_L6 ; B = FM_CPU1_XTRIG_L6
C2558  Q_CAP  22UF 4V 20% X6S  pkg C0402  page 70 : A = PVDDCR_SOC_P0 ; B = GND

(kicad_pcb
	(version 20260206)
	(generator "pcbnew")
	(generator_version "10.0")
	(general
		(thickness 1.6)
		(legacy_teardrops no)
	)
	(paper "A4")
	(title_block
		(title "04192023_DAF0TMB3IC0_F0TG_MB_C_brd_V02_OCP.brd")
		(comment 1 "Grand Teton / footprints 8040-8041 of 8354")
	)
	(layers
		(0 "F.Cu" signal "TOP")
		(4 "In1.Cu" signal "GND")
		(6 "In2.Cu" signal "IN1")
		(8 "In3.Cu" signal "GND1")
		(10 "In4.Cu" signal "IN2")
		(12 "In5.Cu" signal "GND2")
		(14 "In6.Cu" signal "IN3")
		(16 "In7.Cu" signal "GND3")
		(18 "In8.Cu" signal "VCC")
		(20 "In9.Cu" signal "VCC1")
		(22 "In10.Cu" signal "GND4")
		(24 "In11.Cu" signal "IN4")
		(26 "In12.Cu" signal "GND5")
		(28 "In13.Cu" signal "IN5")
		(30 "In14.Cu" signal "GND6")
		(32 "In15.Cu" signal "IN6")
		(34 "In16.Cu" signal "GND7")
		(2 "B.Cu" signal "BOTTOM")
		(9 "F.Adhes" user "F.Adhesive")
		(11 "B.Adhes" user "B.Adhesive")
		(13 "F.Paste" user "Package Geometry/Pastemask Top")
		(15 "B.Paste" user "Package Geometry/Pastemask Bottom")
		(5 "F.SilkS" user "Ref Des/Silkscreen Top")
		(7 "B.SilkS" user "Ref Des/Silkscreen Bottom")
		(1 "F.Mask" user "Board Geometry/Soldermask Top")
		(3 "B.Mask" user "Board Geometry/Soldermask Bottom")
		(17 "Dwgs.User" user "User.Drawings")
		(19 "Cmts.User" user "User.Comments")
		(21 "Eco1.User" user "User.Eco1")
		(23 "Eco2.User" user "User.Eco2")
		(25 "Edge.Cuts" user "Board Geometry/Outline")
		(27 "Margin" user)
		(31 "F.CrtYd" user "Package Geometry/Place Bound Top")
		(29 "B.CrtYd" user "Package Geometry/Place Bound Bottom")
		(35 "F.Fab" user "Ref Des/Assembly Top")
		(33 "B.Fab" user "Ref Des/Assembly Bottom")
	)
	(footprint ""
		(layer "B.Cu")
		(at 363.645958 -258.795012 180)
		(property "Reference" "C2558"
			(at 0 0 0)
			(layer "B.SilkS")
			(hide yes)
			(effects
				(font
					(size 1.27 1.27)
				)
				(justify mirror)
			)
		)
		(property "Value" ""
			(at 0 0 0)
			(layer "B.Fab")
			(effects
				(font
					(size 1.27 1.27)
				)
				(justify mirror)
			)
		)
		(duplicate_pad_numbers_are_jumpers no)
		(fp_line
			(start 0.7874 0.4064)
			(end 0.7874 -0.4064)
			(stroke
				(width 0.1524)
				(type default)
			)
			(layer "B.SilkS")
		)
		(fp_line
			(start 0.7874 -0.4064)
			(end -0.7874 -0.4064)
			(stroke
				(width 0.1524)
				(type default)
			)
			(layer "B.SilkS")
		)
		(fp_line
			(start -0.7874 0.4064)
			(end 0.7874 0.4064)
			(stroke
				(width 0.1524)
				(type default)
			)
			(layer "B.SilkS")
		)
		(fp_line
			(start -0.7874 -0.4064)
			(end -0.7874 0.4064)
			(stroke
				(width 0.1524)
				(type default)
			)
			(layer "B.SilkS")
		)
		(fp_line
			(start 0.67945 0.3048)
			(end 0.67945 -0.305054)
			(stroke
				(width 0.1)
				(type default)
			)
			(layer "B.Fab")
		)
		(fp_line
			(start 0.67945 -0.305054)
			(end 0.12065 -0.305054)
			(stroke
				(width 0.1)
				(type default)
			)
			(layer "B.Fab")
		)
		(fp_line
			(start 0.12065 0.3048)
			(end 0.67945 0.3048)
			(stroke
				(width 0.1)
				(type default)
			)
			(layer "B.Fab")
		)
		(fp_line
			(start 0.12065 0.2794)
			(end 0.12065 0.3048)
			(stroke
				(width 0.1)
				(type default)
			)
			(layer "B.Fab")
		)
		(fp_line
			(start 0.12065 -0.2794)
			(end -0.12065 -0.2794)
			(stroke
				(width 0.1)
				(type default)
			)
			(layer "B.Fab")
		)
		(fp_line
			(start 0.12065 -0.305054)
			(end 0.12065 -0.2794)
			(stroke
				(width 0.1)
				(type default)
			)
			(layer "B.Fab")
		)
		(fp_line
			(start -0.120396 0.3048)
			(end -0.120396 0.2794)
			(stroke
				(width 0.1)
				(type default)
			)
			(layer "B.Fab")
		)
		(fp_line
			(start -0.120396 0.2794)
			(end 0.12065 0.2794)
			(stroke
				(width 0.1)
				(type default)
			)
			(layer "B.Fab")
		)
		(fp_line
			(start -0.12065 -0.2794)
			(end -0.12065 -0.3048)
			(stroke
				(width 0.1)
				(type default)
			)
			(layer "B.Fab")
		)
		(fp_line
			(start -0.12065 -0.3048)
			(end -0.67945 -0.3048)
			(stroke
				(width 0.1)
				(type default)
			)
			(layer "B.Fab")
		)
		(fp_line
			(start -0.67945 0.3048)
			(end -0.120396 0.3048)
			(stroke
				(width 0.1)
				(type default)
			)
			(layer "B.Fab")
		)
		(fp_line
			(start -0.67945 -0.3048)
			(end -0.67945 0.3048)
			(stroke
				(width 0.1)
				(type default)
			)
			(layer "B.Fab")
		)
		(pad "1" smd circle
			(at 0.40005 0)
			(size 0 0)
			(layers "B.Cu" "B.Mask" "B.Paste")
			(net "PVDDCR_SOC_P0")
		)
		(pad "2" smd circle
			(at -0.40005 0)
			(size 0 0)
			(layers "B.Cu" "B.Mask" "B.Paste")
			(net "GND")
		)
	)
	(footprint ""
		(layer "B.Cu")
		(at 171.214288 -107.188 180)
		(property "Reference" "R234"
			(at 0 0 0)
			(layer "B.SilkS")
			(hide yes)
			(effects
				(font
					(size 1.27 1.27)
				)
				(justify mirror)
			)
		)
		(property "Value" ""
			(at 0 0 0)
			(layer "B.Fab")
			(effects
				(font
					(size 1.27 1.27)
				)
				(justify mirror)
			)
		)
		(duplicate_pad_numbers_are_jumpers no)
		(fp_line
			(start 0.7874 0.4064)
			(end 0.7874 -0.4064)
			(stroke
				(width 0.1524)
				(type default)
			)
			(layer "B.SilkS")
		)
		(fp_line
			(start 0.7874 -0.4064)
			(end -0.7874 -0.4064)
			(stroke
				(width 0.1524)
				(type default)
			)
			(layer "B.SilkS")
		)
		(fp_line
			(start -0.7874 0.4064)
			(end 0.7874 0.4064)
			(stroke
				(width 0.1524)
				(type default)
			)
			(layer "B.SilkS")
		)
		(fp_line
			(start -0.7874 -0.4064)
			(end -0.7874 0.4064)
			(stroke
				(width 0.1524)
				(type default)
			)
			(layer "B.SilkS")
		)
		(fp_line
			(start 0.67945 0.3048)
			(end 0.67945 -0.305054)
			(stroke
				(width 0.1)
				(type default)
			)
			(layer "B.Fab")
		)
		(fp_line
			(start 0.67945 -0.305054)
			(end 0.12065 -0.305054)
			(stroke
				(width 0.1)
				(type default)
			)
			(layer "B.Fab")
		)
		(fp_line
			(start 0.12065 0.3048)
			(end 0.67945 0.3048)
			(stroke
				(width 0.1)
				(type default)
			)
			(layer "B.Fab")
		)
		(fp_line
			(start 0.12065 0.2794)
			(end 0.12065 0.3048)
			(stroke
				(width 0.1)
				(type default)
			)
			(layer "B.Fab")
		)
		(fp_line
			(start 0.12065 -0.2794)
			(end -0.12065 -0.2794)
			(stroke
				(width 0.1)
				(type default)
			)
			(layer "B.Fab")
		)
		(fp_line
			(start 0.12065 -0.305054)
			(end 0.12065 -0.2794)
			(stroke
				(width 0.1)
				(type default)
			)
			(layer "B.Fab")
		)
		(fp_line
			(start -0.120396 0.3048)
			(end -0.120396 0.2794)
			(stroke
				(width 0.1)
				(type default)
			)
			(layer "B.Fab")
		)
		(fp_line
			(start -0.120396 0.2794)
			(end 0.12065 0.2794)
			(stroke
				(width 0.1)
				(type default)
			)
			(layer "B.Fab")
		)
		(fp_line
			(start -0.12065 -0.2794)
			(end -0.12065 -0.3048)
			(stroke
				(width 0.1)
				(type default)
			)
			(layer "B.Fab")
		)
		(fp_line
			(start -0.12065 -0.3048)
			(end -0.67945 -0.3048)
			(stroke
				(width 0.1)
				(type default)
			)
			(layer "B.Fab")
		)
		(fp_line
			(start -0.67945 0.3048)
			(end -0.120396 0.3048)
			(stroke
				(width 0.1)
				(type default)
			)
			(layer "B.Fab")
		)
		(fp_line
			(start -0.67945 -0.3048)
			(end -0.67945 0.3048)
			(stroke
				(width 0.1)
				(type default)
			)
			(layer "B.Fab")
		)
		(pad "1" smd circle
			(at 0.40005 0)
			(size 0 0)
			(layers "B.Cu" "B.Mask" "B.Paste")
			(net "CPU1_XTRIG_L6")
		)
		(pad "2" smd circle
			(at -0.40005 0)
			(size 0 0)
			(layers "B.Cu" "B.Mask" "B.Paste")
			(net "FM_CPU1_XTRIG_L6")
		)
	)
)
